(kicad_pcb
	(version 20241229)
	(generator "pcbnew")
	(generator_version "9.0")
	(general
		(thickness 1.599998)
		(legacy_teardrops no)
	)
	(paper "A4")
	(title_block
		(title "Artix - Datacenter Secure Control Module (DC-SCM)")
		(date "2024-11-06")
		(rev "1.1.3")
		(comment 9 "footprint 266 of 544 (U7), pads 77-96 of 96")
	)
	(layers
		(0 "F.Cu" signal)
		(4 "In1.Cu" signal)
		(6 "In2.Cu" signal)
		(8 "In3.Cu" signal)
		(10 "In4.Cu" signal)
		(12 "In5.Cu" signal)
		(14 "In6.Cu" signal)
		(2 "B.Cu" signal)
		(9 "F.Adhes" user "F.Adhesive")
		(11 "B.Adhes" user "B.Adhesive")
		(13 "F.Paste" user)
		(15 "B.Paste" user)
		(5 "F.SilkS" user "F.Silkscreen")
		(7 "B.SilkS" user "B.Silkscreen")
		(1 "F.Mask" user)
		(3 "B.Mask" user)
		(17 "Dwgs.User" user "User.Drawings")
		(19 "Cmts.User" user "User.Comments")
		(21 "Eco1.User" user "User.Eco1")
		(23 "Eco2.User" user "User.Eco2")
		(25 "Edge.Cuts" user)
		(27 "Margin" user)
		(31 "F.CrtYd" user "F.Courtyard")
		(29 "B.CrtYd" user "B.Courtyard")
		(35 "F.Fab" user)
		(33 "B.Fab" user)
	)
	(footprint "antmicro-footprints:BGA-96-48_7.5x13.5mm_Layout9x16_P0.8mm"
		(layer "F.Cu")
		(at 98.175 147.175 90)
		(descr "Based on: https://www.alliancememory.com/wp-content/uploads/AllianceMemory_4G_DDR3L_AS4C256M16D3LC_March2020_Rev1.0.pdf")
		(property "Reference" "U7"
			(at -4 -7.3 90)
			(layer "F.SilkS")
			(effects
				(font
					(size 0.7 0.7)
					(thickness 0.15)
				)
				(justify left bottom)
			)
		)
		(property "Value" "AS4C256M16D3"
			(at -4 7.85 90)
			(layer "F.Fab")
			(effects
				(font
					(size 0.7 0.7)
					(thickness 0.15)
				)
				(justify left bottom)
			)
		)
		(property "Datasheet" "https://www.alliancememory.com/wp-content/uploads/AllianceMemory_4G_DDR3L_AS4C256M16D3LC_March2020_Rev1.0.pdf"
			(at 0 0 90)
			(layer "F.Fab")
			(effects
				(font
					(size 0.7 0.7)
					(thickness 0.15)
				)
				(justify left bottom)
			)
		)
		(property "Description" "SDRAM - DDR3 Memory IC 4Gbit Parallel 800 MHz 20 ns 96-FBGA (9x13)"
			(at 0 0 90)
			(layer "F.Fab")
			(effects
				(font
					(size 0.7 0.7)
					(thickness 0.15)
				)
				(justify left bottom)
			)
		)
		(property "Manufacturer" "Alliance Memory"
			(at 0 0 90)
			(unlocked yes)
			(layer "F.Fab")
			(hide yes)
			(effects
				(font
					(size 1 1)
					(thickness 0.15)
				)
			)
		)
		(property "MPN" "AS4C256M16D3LC-12BCN"
			(at 0 0 90)
			(unlocked yes)
			(layer "F.Fab")
			(hide yes)
			(effects
				(font
					(size 1 1)
					(thickness 0.15)
				)
			)
		)
		(property "Author" "Antmicro"
			(at 0 0 90)
			(unlocked yes)
			(layer "F.Fab")
			(hide yes)
			(effects
				(font
					(size 1 1)
					(thickness 0.15)
				)
			)
		)
		(property "License" "Apache-2.0"
			(at 0 0 90)
			(unlocked yes)
			(layer "F.Fab")
			(hide yes)
			(effects
				(font
					(size 1 1)
					(thickness 0.15)
				)
			)
		)
		(sheetname "/DDR3/")
		(sheetfile "ddr3.kicad_sch")
		(attr smd)
		(pad "N8" smd circle
			(at 2.4 3.6 180)
			(size 0.41 0.41)
			(layers "F.Cu" "F.Mask" "F.Paste")
			(net 155 "DDR3_BA1")
			(pinfunction "BA1")
			(pintype "input")
			(solder_mask_margin 0.03)
		)
		(pad "N9" smd circle
			(at 3.2 3.6 180)
			(size 0.41 0.41)
			(layers "F.Cu" "F.Mask" "F.Paste")
			(net 3 "VCC1V35")
			(pinfunction "VDD")
			(pintype "passive")
			(solder_mask_margin 0.03)
		)
		(pad "P1" smd circle
			(at -3.2 4.4 180)
			(size 0.41 0.41)
			(layers "F.Cu" "F.Mask" "F.Paste")
			(net 1 "GND")
			(pinfunction "VSS")
			(pintype "passive")
			(solder_mask_margin 0.03)
		)
		(pad "P2" smd circle
			(at -2.4 4.4 180)
			(size 0.41 0.41)
			(layers "F.Cu" "F.Mask" "F.Paste")
			(net 167 "DDR3_A5")
			(pinfunction "A5")
			(pintype "input")
			(solder_mask_margin 0.03)
		)
		(pad "P3" smd circle
			(at -1.6 4.4 180)
			(size 0.41 0.41)
			(layers "F.Cu" "F.Mask" "F.Paste")
			(net 147 "DDR3_A2")
			(pinfunction "A2")
			(pintype "input")
			(solder_mask_margin 0.03)
		)
		(pad "P7" smd circle
			(at 1.6 4.4 180)
			(size 0.41 0.41)
			(layers "F.Cu" "F.Mask" "F.Paste")
			(net 157 "DDR3_A1")
			(pinfunction "A1")
			(pintype "input")
			(solder_mask_margin 0.03)
		)
		(pad "P8" smd circle
			(at 2.4 4.4 180)
			(size 0.41 0.41)
			(layers "F.Cu" "F.Mask" "F.Paste")
			(net 159 "DDR3_A4")
			(pinfunction "A4")
			(pintype "input")
			(solder_mask_margin 0.03)
		)
		(pad "P9" smd circle
			(at 3.2 4.4 180)
			(size 0.41 0.41)
			(layers "F.Cu" "F.Mask" "F.Paste")
			(net 1 "GND")
			(pinfunction "VSS")
			(pintype "passive")
			(solder_mask_margin 0.03)
		)
		(pad "R1" smd circle
			(at -3.2 5.2 180)
			(size 0.41 0.41)
			(layers "F.Cu" "F.Mask" "F.Paste")
			(net 3 "VCC1V35")
			(pinfunction "VDD")
			(pintype "passive")
			(solder_mask_margin 0.03)
		)
		(pad "R2" smd circle
			(at -2.4 5.2 180)
			(size 0.41 0.41)
			(layers "F.Cu" "F.Mask" "F.Paste")
			(net 148 "DDR3_A7")
			(pinfunction "A7")
			(pintype "input")
			(solder_mask_margin 0.03)
		)
		(pad "R3" smd circle
			(at -1.6 5.2 180)
			(size 0.41 0.41)
			(layers "F.Cu" "F.Mask" "F.Paste")
			(net 149 "DDR3_A9")
			(pinfunction "A9")
			(pintype "input")
			(solder_mask_margin 0.03)
		)
		(pad "R7" smd circle
			(at 1.6 5.2 180)
			(size 0.41 0.41)
			(layers "F.Cu" "F.Mask" "F.Paste")
			(net 150 "DDR3_A11")
			(pinfunction "A11")
			(pintype "input")
			(solder_mask_margin 0.03)
		)
		(pad "R8" smd circle
			(at 2.4 5.2 180)
			(size 0.41 0.41)
			(layers "F.Cu" "F.Mask" "F.Paste")
			(net 146 "DDR3_A6")
			(pinfunction "A6")
			(pintype "input")
			(solder_mask_margin 0.03)
		)
		(pad "R9" smd circle
			(at 3.2 5.2 180)
			(size 0.41 0.41)
			(layers "F.Cu" "F.Mask" "F.Paste")
			(net 3 "VCC1V35")
			(pinfunction "VDD")
			(pintype "passive")
			(solder_mask_margin 0.03)
		)
		(pad "T1" smd circle
			(at -3.2 6 180)
			(size 0.41 0.41)
			(layers "F.Cu" "F.Mask" "F.Paste")
			(net 1 "GND")
			(pinfunction "VSS")
			(pintype "passive")
			(solder_mask_margin 0.03)
		)
		(pad "T2" smd circle
			(at -2.4 6 180)
			(size 0.41 0.41)
			(layers "F.Cu" "F.Mask" "F.Paste")
			(net 191 "DDR3_RESET")
			(pinfunction "~{RESET}")
			(pintype "input")
			(solder_mask_margin 0.03)
		)
		(pad "T3" smd circle
			(at -1.6 6 180)
			(size 0.41 0.41)
			(layers "F.Cu" "F.Mask" "F.Paste")
			(net 151 "DDR3_A13")
			(pinfunction "A13")
			(pintype "input")
			(solder_mask_margin 0.03)
		)
		(pad "T7" smd circle
			(at 1.6 6 180)
			(size 0.41 0.41)
			(layers "F.Cu" "F.Mask" "F.Paste")
			(net 144 "DDR3_A14")
			(pinfunction "A14")
			(pintype "input")
			(solder_mask_margin 0.03)
		)
		(pad "T8" smd circle
			(at 2.4 6 180)
			(size 0.41 0.41)
			(layers "F.Cu" "F.Mask" "F.Paste")
			(net 145 "DDR3_A8")
			(pinfunction "A8")
			(pintype "input")
			(solder_mask_margin 0.03)
		)
		(pad "T9" smd circle
			(at 3.2 6 180)
			(size 0.41 0.41)
			(layers "F.Cu" "F.Mask" "F.Paste")
			(net 1 "GND")
			(pinfunction "VSS")
			(pintype "passive")
			(solder_mask_margin 0.03)
		)
	)
)
